(kicad_pcb
	(version 20260206)
	(generator "pcbnew")
	(generator_version "10.0")
	(general
		(thickness 1.6)
		(legacy_teardrops no)
	)
	(paper "A4")
	(title_block
		(title "01162023_DA0F0TEBIF0_F0T_Expander_BD_F_brd_V02_OCP.brd")
		(comment 1 "Grand Teton / footprints 3848-3854 of 9728")
	)
	(layers
		(0 "F.Cu" signal "TOP")
		(4 "In1.Cu" signal "GND")
		(6 "In2.Cu" signal "VCC")
		(8 "In3.Cu" signal "VCC1")
		(10 "In4.Cu" signal "GND1")
		(12 "In5.Cu" signal "IN1")
		(14 "In6.Cu" signal "GND2")
		(16 "In7.Cu" signal "IN2")
		(18 "In8.Cu" signal "GND3")
		(20 "In9.Cu" signal "IN3")
		(22 "In10.Cu" signal "GND4")
		(24 "In11.Cu" signal "IN4")
		(26 "In12.Cu" signal "GND5")
		(28 "In13.Cu" signal "IN5")
		(30 "In14.Cu" signal "GND6")
		(32 "In15.Cu" signal "IN6")
		(34 "In16.Cu" signal "GND7")
		(2 "B.Cu" signal "BOTTOM")
		(9 "F.Adhes" user "F.Adhesive")
		(11 "B.Adhes" user "B.Adhesive")
		(13 "F.Paste" user "Package Geometry/Pastemask Top")
		(15 "B.Paste" user "Package Geometry/Pastemask Bottom")
		(5 "F.SilkS" user "Ref Des/Silkscreen Top")
		(7 "B.SilkS" user "Ref Des/Silkscreen Bottom")
		(1 "F.Mask" user "Board Geometry/Soldermask Top")
		(3 "B.Mask" user "Board Geometry/Soldermask Bottom")
		(17 "Dwgs.User" user "User.Drawings")
		(19 "Cmts.User" user "User.Comments")
		(21 "Eco1.User" user "User.Eco1")
		(23 "Eco2.User" user "User.Eco2")
		(25 "Edge.Cuts" user "Board Geometry/Outline")
		(27 "Margin" user)
		(31 "F.CrtYd" user "Package Geometry/Place Bound Top")
		(29 "B.CrtYd" user "Package Geometry/Place Bound Bottom")
		(35 "F.Fab" user "Ref Des/Assembly Top")
		(33 "B.Fab" user "Ref Des/Assembly Bottom")
	)
	(footprint ""
		(layer "F.Cu")
		(at 248.902728 -112.139476 -90)
		(property "Reference" "PC904"
			(at 0 0 270)
			(layer "F.SilkS")
			(hide yes)
			(effects
				(font
					(size 1.27 1.27)
				)
			)
		)
		(property "Value" ""
			(at 0 0 270)
			(layer "F.Fab")
			(effects
				(font
					(size 1.27 1.27)
				)
			)
		)
		(duplicate_pad_numbers_are_jumpers no)
		(fp_line
			(start -0.7874 0.4064)
			(end -0.7874 -0.4064)
			(stroke
				(width 0.1524)
				(type default)
			)
			(layer "F.SilkS")
		)
		(fp_line
			(start 0.7874 0.4064)
			(end -0.7874 0.4064)
			(stroke
				(width 0.1524)
				(type default)
			)
			(layer "F.SilkS")
		)
		(fp_line
			(start -0.7874 -0.4064)
			(end 0.7874 -0.4064)
			(stroke
				(width 0.1524)
				(type default)
			)
			(layer "F.SilkS")
		)
		(fp_line
			(start 0.7874 -0.4064)
			(end 0.7874 0.4064)
			(stroke
				(width 0.1524)
				(type default)
			)
			(layer "F.SilkS")
		)
		(fp_line
			(start -0.67945 0.3048)
			(end -0.67945 -0.305054)
			(stroke
				(width 0.1)
				(type default)
			)
			(layer "F.Fab")
		)
		(fp_line
			(start -0.12065 0.3048)
			(end -0.67945 0.3048)
			(stroke
				(width 0.1)
				(type default)
			)
			(layer "F.Fab")
		)
		(fp_line
			(start 0.120396 0.3048)
			(end 0.120396 0.2794)
			(stroke
				(width 0.1)
				(type default)
			)
			(layer "F.Fab")
		)
		(fp_line
			(start 0.67945 0.3048)
			(end 0.120396 0.3048)
			(stroke
				(width 0.1)
				(type default)
			)
			(layer "F.Fab")
		)
		(fp_line
			(start -0.12065 0.2794)
			(end -0.12065 0.3048)
			(stroke
				(width 0.1)
				(type default)
			)
			(layer "F.Fab")
		)
		(fp_line
			(start 0.120396 0.2794)
			(end -0.12065 0.2794)
			(stroke
				(width 0.1)
				(type default)
			)
			(layer "F.Fab")
		)
		(fp_line
			(start -0.12065 -0.2794)
			(end 0.12065 -0.2794)
			(stroke
				(width 0.1)
				(type default)
			)
			(layer "F.Fab")
		)
		(fp_line
			(start 0.12065 -0.2794)
			(end 0.12065 -0.3048)
			(stroke
				(width 0.1)
				(type default)
			)
			(layer "F.Fab")
		)
		(fp_line
			(start 0.12065 -0.3048)
			(end 0.67945 -0.3048)
			(stroke
				(width 0.1)
				(type default)
			)
			(layer "F.Fab")
		)
		(fp_line
			(start 0.67945 -0.3048)
			(end 0.67945 0.3048)
			(stroke
				(width 0.1)
				(type default)
			)
			(layer "F.Fab")
		)
		(fp_line
			(start -0.67945 -0.305054)
			(end -0.12065 -0.305054)
			(stroke
				(width 0.1)
				(type default)
			)
			(layer "F.Fab")
		)
		(fp_line
			(start -0.12065 -0.305054)
			(end -0.12065 -0.2794)
			(stroke
				(width 0.1)
				(type default)
			)
			(layer "F.Fab")
		)
		(pad "1" smd circle
			(at -0.40005 0 270)
			(size 0 0)
			(layers "F.Cu" "F.Mask" "F.Paste")
			(net "P3V3_NIC4_CO_MODE")
		)
		(pad "2" smd circle
			(at 0.40005 0 270)
			(size 0 0)
			(layers "F.Cu" "F.Mask" "F.Paste")
			(net "GND")
		)
	)
	(footprint ""
		(layer "F.Cu")
		(at 215.047322 -19.33956)
		(property "Reference" "C3927"
			(at 0 0 0)
			(layer "F.SilkS")
			(hide yes)
			(effects
				(font
					(size 1.27 1.27)
				)
			)
		)
		(property "Value" ""
			(at 0 0 0)
			(layer "F.Fab")
			(effects
				(font
					(size 1.27 1.27)
				)
			)
		)
		(duplicate_pad_numbers_are_jumpers no)
		(fp_line
			(start -0.7874 -0.4064)
			(end 0.7874 -0.4064)
			(stroke
				(width 0.1524)
				(type default)
			)
			(layer "F.SilkS")
		)
		(fp_line
			(start -0.7874 0.4064)
			(end -0.7874 -0.4064)
			(stroke
				(width 0.1524)
				(type default)
			)
			(layer "F.SilkS")
		)
		(fp_line
			(start 0.7874 -0.4064)
			(end 0.7874 0.4064)
			(stroke
				(width 0.1524)
				(type default)
			)
			(layer "F.SilkS")
		)
		(fp_line
			(start 0.7874 0.4064)
			(end -0.7874 0.4064)
			(stroke
				(width 0.1524)
				(type default)
			)
			(layer "F.SilkS")
		)
		(fp_line
			(start -0.67945 -0.305054)
			(end -0.12065 -0.305054)
			(stroke
				(width 0.1)
				(type default)
			)
			(layer "F.Fab")
		)
		(fp_line
			(start -0.67945 0.3048)
			(end -0.67945 -0.305054)
			(stroke
				(width 0.1)
				(type default)
			)
			(layer "F.Fab")
		)
		(fp_line
			(start -0.12065 -0.305054)
			(end -0.12065 -0.2794)
			(stroke
				(width 0.1)
				(type default)
			)
			(layer "F.Fab")
		)
		(fp_line
			(start -0.12065 -0.2794)
			(end 0.12065 -0.2794)
			(stroke
				(width 0.1)
				(type default)
			)
			(layer "F.Fab")
		)
		(fp_line
			(start -0.12065 0.2794)
			(end -0.12065 0.3048)
			(stroke
				(width 0.1)
				(type default)
			)
			(layer "F.Fab")
		)
		(fp_line
			(start -0.12065 0.3048)
			(end -0.67945 0.3048)
			(stroke
				(width 0.1)
				(type default)
			)
			(layer "F.Fab")
		)
		(fp_line
			(start 0.120396 0.2794)
			(end -0.12065 0.2794)
			(stroke
				(width 0.1)
				(type default)
			)
			(layer "F.Fab")
		)
		(fp_line
			(start 0.120396 0.3048)
			(end 0.120396 0.2794)
			(stroke
				(width 0.1)
				(type default)
			)
			(layer "F.Fab")
		)
		(fp_line
			(start 0.12065 -0.3048)
			(end 0.67945 -0.3048)
			(stroke
				(width 0.1)
				(type default)
			)
			(layer "F.Fab")
		)
		(fp_line
			(start 0.12065 -0.2794)
			(end 0.12065 -0.3048)
			(stroke
				(width 0.1)
				(type default)
			)
			(layer "F.Fab")
		)
		(fp_line
			(start 0.67945 -0.3048)
			(end 0.67945 0.3048)
			(stroke
				(width 0.1)
				(type default)
			)
			(layer "F.Fab")
		)
		(fp_line
			(start 0.67945 0.3048)
			(end 0.120396 0.3048)
			(stroke
				(width 0.1)
				(type default)
			)
			(layer "F.Fab")
		)
		(pad "1" smd circle
			(at -0.40005 0)
			(size 0 0)
			(layers "F.Cu" "F.Mask" "F.Paste")
			(net "P12V_SSD7")
		)
		(pad "2" smd circle
			(at 0.40005 0)
			(size 0 0)
			(layers "F.Cu" "F.Mask" "F.Paste")
			(net "GND")
		)
	)
	(footprint ""
		(layer "F.Cu")
		(at 63.6778 -113.251742)
		(property "Reference" "R86"
			(at 0 0 0)
			(layer "F.SilkS")
			(hide yes)
			(effects
				(font
					(size 1.27 1.27)
				)
			)
		)
		(property "Value" ""
			(at 0 0 0)
			(layer "F.Fab")
			(effects
				(font
					(size 1.27 1.27)
				)
			)
		)
		(duplicate_pad_numbers_are_jumpers no)
		(fp_line
			(start -0.7874 -0.4064)
			(end 0.7874 -0.4064)
			(stroke
				(width 0.1524)
				(type default)
			)
			(layer "F.SilkS")
		)
		(fp_line
			(start -0.7874 0.4064)
			(end -0.7874 -0.4064)
			(stroke
				(width 0.1524)
				(type default)
			)
			(layer "F.SilkS")
		)
		(fp_line
			(start 0.7874 -0.4064)
			(end 0.7874 0.4064)
			(stroke
				(width 0.1524)
				(type default)
			)
			(layer "F.SilkS")
		)
		(fp_line
			(start 0.7874 0.4064)
			(end -0.7874 0.4064)
			(stroke
				(width 0.1524)
				(type default)
			)
			(layer "F.SilkS")
		)
		(fp_line
			(start -0.67945 -0.305054)
			(end -0.12065 -0.305054)
			(stroke
				(width 0.1)
				(type default)
			)
			(layer "F.Fab")
		)
		(fp_line
			(start -0.67945 0.3048)
			(end -0.67945 -0.305054)
			(stroke
				(width 0.1)
				(type default)
			)
			(layer "F.Fab")
		)
		(fp_line
			(start -0.12065 -0.305054)
			(end -0.12065 -0.2794)
			(stroke
				(width 0.1)
				(type default)
			)
			(layer "F.Fab")
		)
		(fp_line
			(start -0.12065 -0.2794)
			(end 0.12065 -0.2794)
			(stroke
				(width 0.1)
				(type default)
			)
			(layer "F.Fab")
		)
		(fp_line
			(start -0.12065 0.2794)
			(end -0.12065 0.3048)
			(stroke
				(width 0.1)
				(type default)
			)
			(layer "F.Fab")
		)
		(fp_line
			(start -0.12065 0.3048)
			(end -0.67945 0.3048)
			(stroke
				(width 0.1)
				(type default)
			)
			(layer "F.Fab")
		)
		(fp_line
			(start 0.120396 0.2794)
			(end -0.12065 0.2794)
			(stroke
				(width 0.1)
				(type default)
			)
			(layer "F.Fab")
		)
		(fp_line
			(start 0.120396 0.3048)
			(end 0.120396 0.2794)
			(stroke
				(width 0.1)
				(type default)
			)
			(layer "F.Fab")
		)
		(fp_line
			(start 0.12065 -0.3048)
			(end 0.67945 -0.3048)
			(stroke
				(width 0.1)
				(type default)
			)
			(layer "F.Fab")
		)
		(fp_line
			(start 0.12065 -0.2794)
			(end 0.12065 -0.3048)
			(stroke
				(width 0.1)
				(type default)
			)
			(layer "F.Fab")
		)
		(fp_line
			(start 0.67945 -0.3048)
			(end 0.67945 0.3048)
			(stroke
				(width 0.1)
				(type default)
			)
			(layer "F.Fab")
		)
		(fp_line
			(start 0.67945 0.3048)
			(end 0.120396 0.3048)
			(stroke
				(width 0.1)
				(type default)
			)
			(layer "F.Fab")
		)
		(pad "1" smd circle
			(at -0.40005 0)
			(size 0 0)
			(layers "F.Cu" "F.Mask" "F.Paste")
			(net "RST_SMB_NIC1_MUX_ISO_N")
		)
		(pad "2" smd circle
			(at 0.40005 0)
			(size 0 0)
			(layers "F.Cu" "F.Mask" "F.Paste")
			(net "P3V3_NIC1")
		)
	)
	(footprint ""
		(layer "F.Cu")
		(at 268.734286 -250.070874 -90)
		(property "Reference" "R1342"
			(at 0 0 270)
			(layer "F.SilkS")
			(hide yes)
			(effects
				(font
					(size 1.27 1.27)
				)
			)
		)
		(property "Value" ""
			(at 0 0 270)
			(layer "F.Fab")
			(effects
				(font
					(size 1.27 1.27)
				)
			)
		)
		(duplicate_pad_numbers_are_jumpers no)
		(fp_line
			(start -0.7874 0.4064)
			(end -0.7874 -0.4064)
			(stroke
				(width 0.1524)
				(type default)
			)
			(layer "F.SilkS")
		)
		(fp_line
			(start 0.7874 0.4064)
			(end -0.7874 0.4064)
			(stroke
				(width 0.1524)
				(type default)
			)
			(layer "F.SilkS")
		)
		(fp_line
			(start -0.7874 -0.4064)
			(end 0.7874 -0.4064)
			(stroke
				(width 0.1524)
				(type default)
			)
			(layer "F.SilkS")
		)
		(fp_line
			(start 0.7874 -0.4064)
			(end 0.7874 0.4064)
			(stroke
				(width 0.1524)
				(type default)
			)
			(layer "F.SilkS")
		)
		(fp_line
			(start -0.67945 0.3048)
			(end -0.67945 -0.305054)
			(stroke
				(width 0.1)
				(type default)
			)
			(layer "F.Fab")
		)
		(fp_line
			(start -0.12065 0.3048)
			(end -0.67945 0.3048)
			(stroke
				(width 0.1)
				(type default)
			)
			(layer "F.Fab")
		)
		(fp_line
			(start 0.120396 0.3048)
			(end 0.120396 0.2794)
			(stroke
				(width 0.1)
				(type default)
			)
			(layer "F.Fab")
		)
		(fp_line
			(start 0.67945 0.3048)
			(end 0.120396 0.3048)
			(stroke
				(width 0.1)
				(type default)
			)
			(layer "F.Fab")
		)
		(fp_line
			(start -0.12065 0.2794)
			(end -0.12065 0.3048)
			(stroke
				(width 0.1)
				(type default)
			)
			(layer "F.Fab")
		)
		(fp_line
			(start 0.120396 0.2794)
			(end -0.12065 0.2794)
			(stroke
				(width 0.1)
				(type default)
			)
			(layer "F.Fab")
		)
		(fp_line
			(start -0.12065 -0.2794)
			(end 0.12065 -0.2794)
			(stroke
				(width 0.1)
				(type default)
			)
			(layer "F.Fab")
		)
		(fp_line
			(start 0.12065 -0.2794)
			(end 0.12065 -0.3048)
			(stroke
				(width 0.1)
				(type default)
			)
			(layer "F.Fab")
		)
		(fp_line
			(start 0.12065 -0.3048)
			(end 0.67945 -0.3048)
			(stroke
				(width 0.1)
				(type default)
			)
			(layer "F.Fab")
		)
		(fp_line
			(start 0.67945 -0.3048)
			(end 0.67945 0.3048)
			(stroke
				(width 0.1)
				(type default)
			)
			(layer "F.Fab")
		)
		(fp_line
			(start -0.67945 -0.305054)
			(end -0.12065 -0.305054)
			(stroke
				(width 0.1)
				(type default)
			)
			(layer "F.Fab")
		)
		(fp_line
			(start -0.12065 -0.305054)
			(end -0.12065 -0.2794)
			(stroke
				(width 0.1)
				(type default)
			)
			(layer "F.Fab")
		)
		(pad "1" smd circle
			(at -0.40005 0 270)
			(size 0 0)
			(layers "F.Cu" "F.Mask" "F.Paste")
			(net "PEX2_MODE_SEL6")
		)
		(pad "2" smd circle
			(at 0.40005 0 270)
			(size 0 0)
			(layers "F.Cu" "F.Mask" "F.Paste")
			(net "P1V8_PEX")
		)
	)
	(footprint ""
		(layer "F.Cu")
		(at 219.825316 -124.790962 180)
		(property "Reference" "R5965"
			(at 0 0 180)
			(layer "F.SilkS")
			(hide yes)
			(effects
				(font
					(size 1.27 1.27)
				)
			)
		)
		(property "Value" ""
			(at 0 0 180)
			(layer "F.Fab")
			(effects
				(font
					(size 1.27 1.27)
				)
			)
		)
		(duplicate_pad_numbers_are_jumpers no)
		(fp_line
			(start 0.7874 0.4064)
			(end -0.7874 0.4064)
			(stroke
				(width 0.1524)
				(type default)
			)
			(layer "F.SilkS")
		)
		(fp_line
			(start 0.7874 -0.4064)
			(end 0.7874 0.4064)
			(stroke
				(width 0.1524)
				(type default)
			)
			(layer "F.SilkS")
		)
		(fp_line
			(start -0.7874 0.4064)
			(end -0.7874 -0.4064)
			(stroke
				(width 0.1524)
				(type default)
			)
			(layer "F.SilkS")
		)
		(fp_line
			(start -0.7874 -0.4064)
			(end 0.7874 -0.4064)
			(stroke
				(width 0.1524)
				(type default)
			)
			(layer "F.SilkS")
		)
		(fp_line
			(start 0.67945 0.3048)
			(end 0.120396 0.3048)
			(stroke
				(width 0.1)
				(type default)
			)
			(layer "F.Fab")
		)
		(fp_line
			(start 0.67945 -0.3048)
			(end 0.67945 0.3048)
			(stroke
				(width 0.1)
				(type default)
			)
			(layer "F.Fab")
		)
		(fp_line
			(start 0.12065 -0.2794)
			(end 0.12065 -0.3048)
			(stroke
				(width 0.1)
				(type default)
			)
			(layer "F.Fab")
		)
		(fp_line
			(start 0.12065 -0.3048)
			(end 0.67945 -0.3048)
			(stroke
				(width 0.1)
				(type default)
			)
			(layer "F.Fab")
		)
		(fp_line
			(start 0.120396 0.3048)
			(end 0.120396 0.2794)
			(stroke
				(width 0.1)
				(type default)
			)
			(layer "F.Fab")
		)
		(fp_line
			(start 0.120396 0.2794)
			(end -0.12065 0.2794)
			(stroke
				(width 0.1)
				(type default)
			)
			(layer "F.Fab")
		)
		(fp_line
			(start -0.12065 0.3048)
			(end -0.67945 0.3048)
			(stroke
				(width 0.1)
				(type default)
			)
			(layer "F.Fab")
		)
		(fp_line
			(start -0.12065 0.2794)
			(end -0.12065 0.3048)
			(stroke
				(width 0.1)
				(type default)
			)
			(layer "F.Fab")
		)
		(fp_line
			(start -0.12065 -0.2794)
			(end 0.12065 -0.2794)
			(stroke
				(width 0.1)
				(type default)
			)
			(layer "F.Fab")
		)
		(fp_line
			(start -0.12065 -0.305054)
			(end -0.12065 -0.2794)
			(stroke
				(width 0.1)
				(type default)
			)
			(layer "F.Fab")
		)
		(fp_line
			(start -0.67945 0.3048)
			(end -0.67945 -0.305054)
			(stroke
				(width 0.1)
				(type default)
			)
			(layer "F.Fab")
		)
		(fp_line
			(start -0.67945 -0.305054)
			(end -0.12065 -0.305054)
			(stroke
				(width 0.1)
				(type default)
			)
			(layer "F.Fab")
		)
		(pad "1" smd circle
			(at -0.40005 0 180)
			(size 0 0)
			(layers "F.Cu" "F.Mask" "F.Paste")
			(net "P3V3_NIC3_PG_G1")
		)
		(pad "2" smd circle
			(at 0.40005 0 180)
			(size 0 0)
			(layers "F.Cu" "F.Mask" "F.Paste")
			(net "GND")
		)
	)
	(footprint ""
		(layer "F.Cu")
		(at 243.793264 -119.105426 -90)
		(property "Reference" "R6032"
			(at 0 0 270)
			(layer "F.SilkS")
			(hide yes)
			(effects
				(font
					(size 1.27 1.27)
				)
			)
		)
		(property "Value" ""
			(at 0 0 270)
			(layer "F.Fab")
			(effects
				(font
					(size 1.27 1.27)
				)
			)
		)
		(duplicate_pad_numbers_are_jumpers no)
		(fp_line
			(start -0.7874 0.4064)
			(end -0.7874 -0.4064)
			(stroke
				(width 0.1524)
				(type default)
			)
			(layer "F.SilkS")
		)
		(fp_line
			(start 0.7874 0.4064)
			(end -0.7874 0.4064)
			(stroke
				(width 0.1524)
				(type default)
			)
			(layer "F.SilkS")
		)
		(fp_line
			(start -0.7874 -0.4064)
			(end 0.7874 -0.4064)
			(stroke
				(width 0.1524)
				(type default)
			)
			(layer "F.SilkS")
		)
		(fp_line
			(start 0.7874 -0.4064)
			(end 0.7874 0.4064)
			(stroke
				(width 0.1524)
				(type default)
			)
			(layer "F.SilkS")
		)
		(fp_line
			(start -0.67945 0.3048)
			(end -0.67945 -0.305054)
			(stroke
				(width 0.1)
				(type default)
			)
			(layer "F.Fab")
		)
		(fp_line
			(start -0.12065 0.3048)
			(end -0.67945 0.3048)
			(stroke
				(width 0.1)
				(type default)
			)
			(layer "F.Fab")
		)
		(fp_line
			(start 0.120396 0.3048)
			(end 0.120396 0.2794)
			(stroke
				(width 0.1)
				(type default)
			)
			(layer "F.Fab")
		)
		(fp_line
			(start 0.67945 0.3048)
			(end 0.120396 0.3048)
			(stroke
				(width 0.1)
				(type default)
			)
			(layer "F.Fab")
		)
		(fp_line
			(start -0.12065 0.2794)
			(end -0.12065 0.3048)
			(stroke
				(width 0.1)
				(type default)
			)
			(layer "F.Fab")
		)
		(fp_line
			(start 0.120396 0.2794)
			(end -0.12065 0.2794)
			(stroke
				(width 0.1)
				(type default)
			)
			(layer "F.Fab")
		)
		(fp_line
			(start -0.12065 -0.2794)
			(end 0.12065 -0.2794)
			(stroke
				(width 0.1)
				(type default)
			)
			(layer "F.Fab")
		)
		(fp_line
			(start 0.12065 -0.2794)
			(end 0.12065 -0.3048)
			(stroke
				(width 0.1)
				(type default)
			)
			(layer "F.Fab")
		)
		(fp_line
			(start 0.12065 -0.3048)
			(end 0.67945 -0.3048)
			(stroke
				(width 0.1)
				(type default)
			)
			(layer "F.Fab")
		)
		(fp_line
			(start 0.67945 -0.3048)
			(end 0.67945 0.3048)
			(stroke
				(width 0.1)
				(type default)
			)
			(layer "F.Fab")
		)
		(fp_line
			(start -0.67945 -0.305054)
			(end -0.12065 -0.305054)
			(stroke
				(width 0.1)
				(type default)
			)
			(layer "F.Fab")
		)
		(fp_line
			(start -0.12065 -0.305054)
			(end -0.12065 -0.2794)
			(stroke
				(width 0.1)
				(type default)
			)
			(layer "F.Fab")
		)
		(pad "1" smd circle
			(at -0.40005 0 270)
			(size 0 0)
			(layers "F.Cu" "F.Mask" "F.Paste")
			(net "P3V3_AUX")
		)
		(pad "2" smd circle
			(at 0.40005 0 270)
			(size 0 0)
			(layers "F.Cu" "F.Mask" "F.Paste")
			(net "PWRGD_P3V3_NIC4_D")
		)
	)
	(footprint ""
		(layer "F.Cu")
		(at 140.731748 -350.098614 90)
		(property "Reference" "C2248"
			(at 0 0 90)
			(layer "F.SilkS")
			(hide yes)
			(effects
				(font
					(size 1.27 1.27)
				)
			)
		)
		(property "Value" ""
			(at 0 0 90)
			(layer "F.Fab")
			(effects
				(font
					(size 1.27 1.27)
				)
			)
		)
		(duplicate_pad_numbers_are_jumpers no)
		(fp_line
			(start 0.299974 -0.150114)
			(end 0.299974 0.150114)
			(stroke
				(width 0.1)
				(type default)
			)
			(layer "F.Fab")
		)
		(fp_line
			(start -0.299974 -0.150114)
			(end 0.299974 -0.150114)
			(stroke
				(width 0.1)
				(type default)
			)
			(layer "F.Fab")
		)
		(fp_line
			(start 0.299974 0.150114)
			(end -0.299974 0.150114)
			(stroke
				(width 0.1)
				(type default)
			)
			(layer "F.Fab")
		)
		(fp_line
			(start -0.299974 0.150114)
			(end -0.299974 -0.150114)
			(stroke
				(width 0.1)
				(type default)
			)
			(layer "F.Fab")
		)
		(pad "1" smd rect
			(at -0.2667 0 90)
			(size 0.3048 0.381)
			(layers "F.Cu" "F.Mask" "F.Paste")
			(net "P5E_PEX1_STN5_TX_DN<93>")
		)
		(pad "2" smd rect
			(at 0.2667 0 90)
			(size 0.3048 0.381)
			(layers "F.Cu" "F.Mask" "F.Paste")
			(net "P5E_PEX1_STN5_TX_C_DN<93>")
		)
	)
)
